# SCM (Grand Teton) — schematic netlist excerpt (pin names and nets, part order shuffled) for the footprints in the layout excerpt that follows; sources: Cadence DE-HDL packaged netlist, KiCad conversion of 12092022_DA0F0TMDCD0_F0T_Management_Board_D_brd_V3_OCP.brd

C19  Q_CAP  0.1UF 25V 10% X7R  pkg 0402  page 30 : A = P3V3_AUX ; B = GND
R517  Q_RES  33.2 1% CHIP  pkg 0402LF  page 32 : A = JTAG_SCM_PLD_TDO ; B = JTAG_SCM_CONN_TDO

(kicad_pcb
	(version 20260206)
	(generator "pcbnew")
	(generator_version "10.0")
	(general
		(thickness 1.6)
		(legacy_teardrops no)
	)
	(paper "A4")
	(title_block
		(title "12092022_DA0F0TMDCD0_F0T_Management_Board_D_brd_V3_OCP.brd")
		(comment 1 "Grand Teton / footprints 129-130 of 1440")
	)
	(layers
		(0 "F.Cu" signal "TOP")
		(4 "In1.Cu" signal "GND")
		(6 "In2.Cu" signal "IN1")
		(8 "In3.Cu" signal "GND1")
		(10 "In4.Cu" signal "IN2")
		(12 "In5.Cu" signal "VCC")
		(14 "In6.Cu" signal "VCC1")
		(16 "In7.Cu" signal "IN3")
		(18 "In8.Cu" signal "GND2")
		(20 "In9.Cu" signal "IN4")
		(22 "In10.Cu" signal "GND3")
		(2 "B.Cu" signal "BOTTOM")
		(9 "F.Adhes" user "F.Adhesive")
		(11 "B.Adhes" user "B.Adhesive")
		(13 "F.Paste" user "Package Geometry/Pastemask Top")
		(15 "B.Paste" user "Package Geometry/Pastemask Bottom")
		(5 "F.SilkS" user "Ref Des/Silkscreen Top")
		(7 "B.SilkS" user "Ref Des/Silkscreen Bottom")
		(1 "F.Mask" user "Board Geometry/Soldermask Top")
		(3 "B.Mask" user "Board Geometry/Soldermask Bottom")
		(17 "Dwgs.User" user "User.Drawings")
		(19 "Cmts.User" user "User.Comments")
		(21 "Eco1.User" user "User.Eco1")
		(23 "Eco2.User" user "User.Eco2")
		(25 "Edge.Cuts" user "Board Geometry/Outline")
		(27 "Margin" user)
		(31 "F.CrtYd" user "Package Geometry/Place Bound Top")
		(29 "B.CrtYd" user "Package Geometry/Place Bound Bottom")
		(35 "F.Fab" user "Ref Des/Assembly Top")
		(33 "B.Fab" user "Ref Des/Assembly Bottom")
	)
	(footprint ""
		(layer "F.Cu")
		(at 23.749 -66.167 90)
		(property "Reference" "C19"
			(at 0 0 90)
			(layer "F.SilkS")
			(hide yes)
			(effects
				(font
					(size 1.27 1.27)
				)
			)
		)
		(property "Value" ""
			(at 0 0 90)
			(layer "F.Fab")
			(effects
				(font
					(size 1.27 1.27)
				)
			)
		)
		(duplicate_pad_numbers_are_jumpers no)
		(fp_line
			(start 0.7874 -0.4064)
			(end 0.7874 0.4064)
			(stroke
				(width 0.1524)
				(type default)
			)
			(layer "F.SilkS")
		)
		(fp_line
			(start -0.7874 -0.4064)
			(end 0.7874 -0.4064)
			(stroke
				(width 0.1524)
				(type default)
			)
			(layer "F.SilkS")
		)
		(fp_line
			(start 0.7874 0.4064)
			(end -0.7874 0.4064)
			(stroke
				(width 0.1524)
				(type default)
			)
			(layer "F.SilkS")
		)
		(fp_line
			(start -0.7874 0.4064)
			(end -0.7874 -0.4064)
			(stroke
				(width 0.1524)
				(type default)
			)
			(layer "F.SilkS")
		)
		(fp_line
			(start -0.12065 -0.305054)
			(end -0.12065 -0.2794)
			(stroke
				(width 0.1)
				(type default)
			)
			(layer "F.Fab")
		)
		(fp_line
			(start -0.67945 -0.305054)
			(end -0.12065 -0.305054)
			(stroke
				(width 0.1)
				(type default)
			)
			(layer "F.Fab")
		)
		(fp_line
			(start 0.67945 -0.3048)
			(end 0.67945 0.3048)
			(stroke
				(width 0.1)
				(type default)
			)
			(layer "F.Fab")
		)
		(fp_line
			(start 0.12065 -0.3048)
			(end 0.67945 -0.3048)
			(stroke
				(width 0.1)
				(type default)
			)
			(layer "F.Fab")
		)
		(fp_line
			(start 0.12065 -0.2794)
			(end 0.12065 -0.3048)
			(stroke
				(width 0.1)
				(type default)
			)
			(layer "F.Fab")
		)
		(fp_line
			(start -0.12065 -0.2794)
			(end 0.12065 -0.2794)
			(stroke
				(width 0.1)
				(type default)
			)
			(layer "F.Fab")
		)
		(fp_line
			(start 0.120396 0.2794)
			(end -0.12065 0.2794)
			(stroke
				(width 0.1)
				(type default)
			)
			(layer "F.Fab")
		)
		(fp_line
			(start -0.12065 0.2794)
			(end -0.12065 0.3048)
			(stroke
				(width 0.1)
				(type default)
			)
			(layer "F.Fab")
		)
		(fp_line
			(start 0.67945 0.3048)
			(end 0.120396 0.3048)
			(stroke
				(width 0.1)
				(type default)
			)
			(layer "F.Fab")
		)
		(fp_line
			(start 0.120396 0.3048)
			(end 0.120396 0.2794)
			(stroke
				(width 0.1)
				(type default)
			)
			(layer "F.Fab")
		)
		(fp_line
			(start -0.12065 0.3048)
			(end -0.67945 0.3048)
			(stroke
				(width 0.1)
				(type default)
			)
			(layer "F.Fab")
		)
		(fp_line
			(start -0.67945 0.3048)
			(end -0.67945 -0.305054)
			(stroke
				(width 0.1)
				(type default)
			)
			(layer "F.Fab")
		)
		(pad "1" smd circle
			(at -0.40005 0 90)
			(size 0 0)
			(layers "F.Cu" "F.Mask" "F.Paste")
			(net "P3V3_AUX")
		)
		(pad "2" smd circle
			(at 0.40005 0 90)
			(size 0 0)
			(layers "F.Cu" "F.Mask" "F.Paste")
			(net "GND")
		)
	)
	(footprint ""
		(layer "F.Cu")
		(at 10.287 -101.854 90)
		(property "Reference" "R517"
			(at 0 0 90)
			(layer "F.SilkS")
			(hide yes)
			(effects
				(font
					(size 1.27 1.27)
				)
			)
		)
		(property "Value" ""
			(at 0 0 90)
			(layer "F.Fab")
			(effects
				(font
					(size 1.27 1.27)
				)
			)
		)
		(duplicate_pad_numbers_are_jumpers no)
		(fp_line
			(start 0.7874 -0.4064)
			(end 0.7874 0.4064)
			(stroke
				(width 0.1524)
				(type default)
			)
			(layer "F.SilkS")
		)
		(fp_line
			(start -0.7874 -0.4064)
			(end 0.7874 -0.4064)
			(stroke
				(width 0.1524)
				(type default)
			)
			(layer "F.SilkS")
		)
		(fp_line
			(start 0.7874 0.4064)
			(end -0.7874 0.4064)
			(stroke
				(width 0.1524)
				(type default)
			)
			(layer "F.SilkS")
		)
		(fp_line
			(start -0.7874 0.4064)
			(end -0.7874 -0.4064)
			(stroke
				(width 0.1524)
				(type default)
			)
			(layer "F.SilkS")
		)
		(fp_line
			(start -0.12065 -0.305054)
			(end -0.12065 -0.2794)
			(stroke
				(width 0.1)
				(type default)
			)
			(layer "F.Fab")
		)
		(fp_line
			(start -0.67945 -0.305054)
			(end -0.12065 -0.305054)
			(stroke
				(width 0.1)
				(type default)
			)
			(layer "F.Fab")
		)
		(fp_line
			(start 0.67945 -0.3048)
			(end 0.67945 0.3048)
			(stroke
				(width 0.1)
				(type default)
			)
			(layer "F.Fab")
		)
		(fp_line
			(start 0.12065 -0.3048)
			(end 0.67945 -0.3048)
			(stroke
				(width 0.1)
				(type default)
			)
			(layer "F.Fab")
		)
		(fp_line
			(start 0.12065 -0.2794)
			(end 0.12065 -0.3048)
			(stroke
				(width 0.1)
				(type default)
			)
			(layer "F.Fab")
		)
		(fp_line
			(start -0.12065 -0.2794)
			(end 0.12065 -0.2794)
			(stroke
				(width 0.1)
				(type default)
			)
			(layer "F.Fab")
		)
		(fp_line
			(start 0.120396 0.2794)
			(end -0.12065 0.2794)
			(stroke
				(width 0.1)
				(type default)
			)
			(layer "F.Fab")
		)
		(fp_line
			(start -0.12065 0.2794)
			(end -0.12065 0.3048)
			(stroke
				(width 0.1)
				(type default)
			)
			(layer "F.Fab")
		)
		(fp_line
			(start 0.67945 0.3048)
			(end 0.120396 0.3048)
			(stroke
				(width 0.1)
				(type default)
			)
			(layer "F.Fab")
		)
		(fp_line
			(start 0.120396 0.3048)
			(end 0.120396 0.2794)
			(stroke
				(width 0.1)
				(type default)
			)
			(layer "F.Fab")
		)
		(fp_line
			(start -0.12065 0.3048)
			(end -0.67945 0.3048)
			(stroke
				(width 0.1)
				(type default)
			)
			(layer "F.Fab")
		)
		(fp_line
			(start -0.67945 0.3048)
			(end -0.67945 -0.305054)
			(stroke
				(width 0.1)
				(type default)
			)
			(layer "F.Fab")
		)
		(pad "1" smd circle
			(at -0.40005 0 90)
			(size 0 0)
			(layers "F.Cu" "F.Mask" "F.Paste")
			(net "JTAG_SCM_PLD_TDO")
		)
		(pad "2" smd circle
			(at 0.40005 0 90)
			(size 0 0)
			(layers "F.Cu" "F.Mask" "F.Paste")
			(net "JTAG_SCM_CONN_TDO")
		)
	)
)
